# S9S_MB_2U (Grand Teton) — schematic netlist excerpt (pin names and nets, part order shuffled) for the footprints in the layout excerpt that follows; sources: Cadence DE-HDL packaged netlist, KiCad conversion of 03242023_DA0F0TMBIJ0_F0T_Motherboard_J_brd_V01_OCP.brd

D75  Q_LED  IC  pkg SMLF  page 253 : A = LED_PWRGD_PVCCFA_EHV_CPU0 ; C = LED_PWRGD_PVCCFA_EHV_CPU0_D
C1973  Q_CAP  1000PF 50V 5% EMPTY  pkg 0402  page 147 : A = GPU_BASE_HMC_READY_ISO ; B = GND

(kicad_pcb
	(version 20260206)
	(generator "pcbnew")
	(generator_version "10.0")
	(general
		(thickness 1.6)
		(legacy_teardrops no)
	)
	(paper "A4")
	(title_block
		(title "03242023_DA0F0TMBIJ0_F0T_Motherboard_J_brd_V01_OCP.brd")
		(comment 1 "Grand Teton / footprints 3185-3186 of 6105")
	)
	(layers
		(0 "F.Cu" signal "TOP")
		(4 "In1.Cu" signal "GND")
		(6 "In2.Cu" signal "IN1")
		(8 "In3.Cu" signal "GND1")
		(10 "In4.Cu" signal "IN2")
		(12 "In5.Cu" signal "GND2")
		(14 "In6.Cu" signal "IN3")
		(16 "In7.Cu" signal "GND3")
		(18 "In8.Cu" signal "VCC")
		(20 "In9.Cu" signal "VCC1")
		(22 "In10.Cu" signal "GND4")
		(24 "In11.Cu" signal "IN4")
		(26 "In12.Cu" signal "GND5")
		(28 "In13.Cu" signal "IN5")
		(30 "In14.Cu" signal "GND6")
		(32 "In15.Cu" signal "IN6")
		(34 "In16.Cu" signal "GND7")
		(2 "B.Cu" signal "BOTTOM")
		(9 "F.Adhes" user "F.Adhesive")
		(11 "B.Adhes" user "B.Adhesive")
		(13 "F.Paste" user "Package Geometry/Pastemask Top")
		(15 "B.Paste" user "Package Geometry/Pastemask Bottom")
		(5 "F.SilkS" user "Ref Des/Silkscreen Top")
		(7 "B.SilkS" user "Ref Des/Silkscreen Bottom")
		(1 "F.Mask" user "Board Geometry/Soldermask Top")
		(3 "B.Mask" user "Board Geometry/Soldermask Bottom")
		(17 "Dwgs.User" user "User.Drawings")
		(19 "Cmts.User" user "User.Comments")
		(21 "Eco1.User" user "User.Eco1")
		(23 "Eco2.User" user "User.Eco2")
		(25 "Edge.Cuts" user "Board Geometry/Outline")
		(27 "Margin" user)
		(31 "F.CrtYd" user "Package Geometry/Place Bound Top")
		(29 "B.CrtYd" user "Package Geometry/Place Bound Bottom")
		(35 "F.Fab" user "Ref Des/Assembly Top")
		(33 "B.Fab" user "Ref Des/Assembly Bottom")
	)
	(footprint ""
		(layer "F.Cu")
		(at 169.422572 -418.479478 180)
		(property "Reference" "C1973"
			(at 0 0 180)
			(layer "F.SilkS")
			(hide yes)
			(effects
				(font
					(size 1.27 1.27)
				)
			)
		)
		(property "Value" ""
			(at 0 0 180)
			(layer "F.Fab")
			(effects
				(font
					(size 1.27 1.27)
				)
			)
		)
		(duplicate_pad_numbers_are_jumpers no)
		(fp_line
			(start 0.7874 0.4064)
			(end -0.7874 0.4064)
			(stroke
				(width 0.1524)
				(type default)
			)
			(layer "F.SilkS")
		)
		(fp_line
			(start 0.7874 -0.4064)
			(end 0.7874 0.4064)
			(stroke
				(width 0.1524)
				(type default)
			)
			(layer "F.SilkS")
		)
		(fp_line
			(start -0.7874 0.4064)
			(end -0.7874 -0.4064)
			(stroke
				(width 0.1524)
				(type default)
			)
			(layer "F.SilkS")
		)
		(fp_line
			(start -0.7874 -0.4064)
			(end 0.7874 -0.4064)
			(stroke
				(width 0.1524)
				(type default)
			)
			(layer "F.SilkS")
		)
		(fp_line
			(start 0.67945 0.3048)
			(end 0.120396 0.3048)
			(stroke
				(width 0.1)
				(type default)
			)
			(layer "F.Fab")
		)
		(fp_line
			(start 0.67945 -0.3048)
			(end 0.67945 0.3048)
			(stroke
				(width 0.1)
				(type default)
			)
			(layer "F.Fab")
		)
		(fp_line
			(start 0.12065 -0.2794)
			(end 0.12065 -0.3048)
			(stroke
				(width 0.1)
				(type default)
			)
			(layer "F.Fab")
		)
		(fp_line
			(start 0.12065 -0.3048)
			(end 0.67945 -0.3048)
			(stroke
				(width 0.1)
				(type default)
			)
			(layer "F.Fab")
		)
		(fp_line
			(start 0.120396 0.3048)
			(end 0.120396 0.2794)
			(stroke
				(width 0.1)
				(type default)
			)
			(layer "F.Fab")
		)
		(fp_line
			(start 0.120396 0.2794)
			(end -0.12065 0.2794)
			(stroke
				(width 0.1)
				(type default)
			)
			(layer "F.Fab")
		)
		(fp_line
			(start -0.12065 0.3048)
			(end -0.67945 0.3048)
			(stroke
				(width 0.1)
				(type default)
			)
			(layer "F.Fab")
		)
		(fp_line
			(start -0.12065 0.2794)
			(end -0.12065 0.3048)
			(stroke
				(width 0.1)
				(type default)
			)
			(layer "F.Fab")
		)
		(fp_line
			(start -0.12065 -0.2794)
			(end 0.12065 -0.2794)
			(stroke
				(width 0.1)
				(type default)
			)
			(layer "F.Fab")
		)
		(fp_line
			(start -0.12065 -0.305054)
			(end -0.12065 -0.2794)
			(stroke
				(width 0.1)
				(type default)
			)
			(layer "F.Fab")
		)
		(fp_line
			(start -0.67945 0.3048)
			(end -0.67945 -0.305054)
			(stroke
				(width 0.1)
				(type default)
			)
			(layer "F.Fab")
		)
		(fp_line
			(start -0.67945 -0.305054)
			(end -0.12065 -0.305054)
			(stroke
				(width 0.1)
				(type default)
			)
			(layer "F.Fab")
		)
		(pad "1" smd circle
			(at -0.40005 0 180)
			(size 0 0)
			(layers "F.Cu" "F.Mask" "F.Paste")
			(net "GPU_BASE_HMC_READY_ISO")
		)
		(pad "2" smd circle
			(at 0.40005 0 180)
			(size 0 0)
			(layers "F.Cu" "F.Mask" "F.Paste")
			(net "GND")
		)
	)
	(footprint ""
		(layer "F.Cu")
		(at 71.194676 -79.078836)
		(property "Reference" "D75"
			(at -37.31641 34.331402 90)
			(unlocked yes)
			(layer "F.SilkS")
			(effects
				(font
					(size 0.635 0.4064)
					(thickness 0.1524)
				)
				(justify left)
			)
		)
		(property "Value" ""
			(at 0 0 0)
			(layer "F.Fab")
			(effects
				(font
					(size 1.27 1.27)
				)
			)
		)
		(duplicate_pad_numbers_are_jumpers no)
		(fp_line
			(start -0.90678 0.4826)
			(end -0.90678 -0.4699)
			(stroke
				(width 0.1524)
				(type default)
			)
			(layer "F.SilkS")
		)
		(fp_line
			(start -0.89408 -0.4826)
			(end 0.90678 -0.4826)
			(stroke
				(width 0.1524)
				(type default)
			)
			(layer "F.SilkS")
		)
		(fp_line
			(start -0.79248 -0.4826)
			(end 1.03378 -0.4826)
			(stroke
				(width 0.1524)
				(type default)
			)
			(layer "F.SilkS")
		)
		(fp_line
			(start -0.64008 -0.4826)
			(end 1.16078 -0.4826)
			(stroke
				(width 0.1524)
				(type default)
			)
			(layer "F.SilkS")
		)
		(fp_line
			(start 0.90678 -0.4826)
			(end 0.90678 0.4826)
			(stroke
				(width 0.1524)
				(type default)
			)
			(layer "F.SilkS")
		)
		(fp_line
			(start 0.90678 0.4826)
			(end -0.90678 0.4826)
			(stroke
				(width 0.1524)
				(type default)
			)
			(layer "F.SilkS")
		)
		(fp_line
			(start 1.03378 -0.4826)
			(end 1.03378 0.4826)
			(stroke
				(width 0.1524)
				(type default)
			)
			(layer "F.SilkS")
		)
		(fp_line
			(start 1.03378 0.4826)
			(end -0.79248 0.4826)
			(stroke
				(width 0.1524)
				(type default)
			)
			(layer "F.SilkS")
		)
		(fp_line
			(start 1.16078 -0.4826)
			(end 1.16078 0.4826)
			(stroke
				(width 0.1524)
				(type default)
			)
			(layer "F.SilkS")
		)
		(fp_line
			(start 1.16078 0.4826)
			(end -0.64008 0.4826)
			(stroke
				(width 0.1524)
				(type default)
			)
			(layer "F.SilkS")
		)
		(fp_line
			(start -0.499872 -0.249936)
			(end 0.499872 -0.249936)
			(stroke
				(width 0.1)
				(type default)
			)
			(layer "F.Fab")
		)
		(fp_line
			(start -0.499872 0.249936)
			(end -0.499872 -0.249936)
			(stroke
				(width 0.1)
				(type default)
			)
			(layer "F.Fab")
		)
		(fp_line
			(start 0.499872 -0.249936)
			(end 0.499872 0.249936)
			(stroke
				(width 0.1)
				(type default)
			)
			(layer "F.Fab")
		)
		(fp_line
			(start 0.499872 0.249936)
			(end -0.499872 0.249936)
			(stroke
				(width 0.1)
				(type default)
			)
			(layer "F.Fab")
		)
		(pad "A" smd rect
			(at -0.47498 0)
			(size 0.6096 0.7112)
			(layers "F.Cu" "F.Mask" "F.Paste")
			(net "LED_PWRGD_PVCCFA_EHV_CPU0")
		)
		(pad "C" smd rect
			(at 0.47498 0)
			(size 0.6096 0.7112)
			(layers "F.Cu" "F.Mask" "F.Paste")
			(net "LED_PWRGD_PVCCFA_EHV_CPU0_D")
		)
	)
)
